# T6G (Grand Teton) — schematic netlist excerpt (pin names and nets, part order shuffled) for the footprints in the layout excerpt that follows; sources: Cadence DE-HDL packaged netlist, KiCad conversion of 04192023_DAF0TMB3IC0_F0TG_MB_C_brd_V02_OCP.brd

PC544_3  Q_CAP  0.1UF 25V 10% X7R  pkg 0402  page 195 : A = PVDDCR_CPU0_P0_VCCS ; B = GND
R6197  Q_RES  0 5% CHIP  pkg 0201LF  page 180 : A = USB2_CPU0_P0_HUB2_R_DN ; B = USB2_HUB_EXT_DN
PR210  Q_RES  5.6 1% CHIP  pkg 0402LF  page 215 : A = SW_PVDDCR_SOC_P1_BOOT2 ; B = SW_PVDDCR_SOC_P1_BOOT2_RC

(kicad_pcb
	(version 20260206)
	(generator "pcbnew")
	(generator_version "10.0")
	(general
		(thickness 1.6)
		(legacy_teardrops no)
	)
	(paper "A4")
	(title_block
		(title "04192023_DAF0TMB3IC0_F0TG_MB_C_brd_V02_OCP.brd")
		(comment 1 "Grand Teton / footprints 3314-3316 of 8354")
	)
	(layers
		(0 "F.Cu" signal "TOP")
		(4 "In1.Cu" signal "GND")
		(6 "In2.Cu" signal "IN1")
		(8 "In3.Cu" signal "GND1")
		(10 "In4.Cu" signal "IN2")
		(12 "In5.Cu" signal "GND2")
		(14 "In6.Cu" signal "IN3")
		(16 "In7.Cu" signal "GND3")
		(18 "In8.Cu" signal "VCC")
		(20 "In9.Cu" signal "VCC1")
		(22 "In10.Cu" signal "GND4")
		(24 "In11.Cu" signal "IN4")
		(26 "In12.Cu" signal "GND5")
		(28 "In13.Cu" signal "IN5")
		(30 "In14.Cu" signal "GND6")
		(32 "In15.Cu" signal "IN6")
		(34 "In16.Cu" signal "GND7")
		(2 "B.Cu" signal "BOTTOM")
		(9 "F.Adhes" user "F.Adhesive")
		(11 "B.Adhes" user "B.Adhesive")
		(13 "F.Paste" user "Package Geometry/Pastemask Top")
		(15 "B.Paste" user "Package Geometry/Pastemask Bottom")
		(5 "F.SilkS" user "Ref Des/Silkscreen Top")
		(7 "B.SilkS" user "Ref Des/Silkscreen Bottom")
		(1 "F.Mask" user "Board Geometry/Soldermask Top")
		(3 "B.Mask" user "Board Geometry/Soldermask Bottom")
		(17 "Dwgs.User" user "User.Drawings")
		(19 "Cmts.User" user "User.Comments")
		(21 "Eco1.User" user "User.Eco1")
		(23 "Eco2.User" user "User.Eco2")
		(25 "Edge.Cuts" user "Board Geometry/Outline")
		(27 "Margin" user)
		(31 "F.CrtYd" user "Package Geometry/Place Bound Top")
		(29 "B.CrtYd" user "Package Geometry/Place Bound Bottom")
		(35 "F.Fab" user "Ref Des/Assembly Top")
		(33 "B.Fab" user "Ref Des/Assembly Bottom")
	)
	(footprint ""
		(layer "F.Cu")
		(at 123.206764 -160.5407 -90)
		(property "Reference" "PR210"
			(at 0 0 270)
			(layer "F.SilkS")
			(hide yes)
			(effects
				(font
					(size 1.27 1.27)
				)
			)
		)
		(property "Value" ""
			(at 0 0 270)
			(layer "F.Fab")
			(effects
				(font
					(size 1.27 1.27)
				)
			)
		)
		(duplicate_pad_numbers_are_jumpers no)
		(fp_line
			(start -0.7874 0.4064)
			(end -0.7874 -0.4064)
			(stroke
				(width 0.1524)
				(type default)
			)
			(layer "F.SilkS")
		)
		(fp_line
			(start 0.7874 0.4064)
			(end -0.7874 0.4064)
			(stroke
				(width 0.1524)
				(type default)
			)
			(layer "F.SilkS")
		)
		(fp_line
			(start -0.7874 -0.4064)
			(end 0.7874 -0.4064)
			(stroke
				(width 0.1524)
				(type default)
			)
			(layer "F.SilkS")
		)
		(fp_line
			(start 0.7874 -0.4064)
			(end 0.7874 0.4064)
			(stroke
				(width 0.1524)
				(type default)
			)
			(layer "F.SilkS")
		)
		(fp_line
			(start -0.67945 0.3048)
			(end -0.67945 -0.305054)
			(stroke
				(width 0.1)
				(type default)
			)
			(layer "F.Fab")
		)
		(fp_line
			(start -0.12065 0.3048)
			(end -0.67945 0.3048)
			(stroke
				(width 0.1)
				(type default)
			)
			(layer "F.Fab")
		)
		(fp_line
			(start 0.120396 0.3048)
			(end 0.120396 0.2794)
			(stroke
				(width 0.1)
				(type default)
			)
			(layer "F.Fab")
		)
		(fp_line
			(start 0.67945 0.3048)
			(end 0.120396 0.3048)
			(stroke
				(width 0.1)
				(type default)
			)
			(layer "F.Fab")
		)
		(fp_line
			(start -0.12065 0.2794)
			(end -0.12065 0.3048)
			(stroke
				(width 0.1)
				(type default)
			)
			(layer "F.Fab")
		)
		(fp_line
			(start 0.120396 0.2794)
			(end -0.12065 0.2794)
			(stroke
				(width 0.1)
				(type default)
			)
			(layer "F.Fab")
		)
		(fp_line
			(start -0.12065 -0.2794)
			(end 0.12065 -0.2794)
			(stroke
				(width 0.1)
				(type default)
			)
			(layer "F.Fab")
		)
		(fp_line
			(start 0.12065 -0.2794)
			(end 0.12065 -0.3048)
			(stroke
				(width 0.1)
				(type default)
			)
			(layer "F.Fab")
		)
		(fp_line
			(start 0.12065 -0.3048)
			(end 0.67945 -0.3048)
			(stroke
				(width 0.1)
				(type default)
			)
			(layer "F.Fab")
		)
		(fp_line
			(start 0.67945 -0.3048)
			(end 0.67945 0.3048)
			(stroke
				(width 0.1)
				(type default)
			)
			(layer "F.Fab")
		)
		(fp_line
			(start -0.67945 -0.305054)
			(end -0.12065 -0.305054)
			(stroke
				(width 0.1)
				(type default)
			)
			(layer "F.Fab")
		)
		(fp_line
			(start -0.12065 -0.305054)
			(end -0.12065 -0.2794)
			(stroke
				(width 0.1)
				(type default)
			)
			(layer "F.Fab")
		)
		(pad "1" smd circle
			(at -0.40005 0 270)
			(size 0 0)
			(layers "F.Cu" "F.Mask" "F.Paste")
			(net "SW_PVDDCR_SOC_P1_BOOT2")
		)
		(pad "2" smd circle
			(at 0.40005 0 270)
			(size 0 0)
			(layers "F.Cu" "F.Mask" "F.Paste")
			(net "SW_PVDDCR_SOC_P1_BOOT2_RC")
		)
	)
	(footprint ""
		(layer "F.Cu")
		(at 135.36168 -28.48102 90)
		(property "Reference" "R6197"
			(at 0 0 90)
			(layer "F.SilkS")
			(hide yes)
			(effects
				(font
					(size 1.27 1.27)
				)
			)
		)
		(property "Value" ""
			(at 0 0 90)
			(layer "F.Fab")
			(effects
				(font
					(size 1.27 1.27)
				)
			)
		)
		(duplicate_pad_numbers_are_jumpers no)
		(fp_line
			(start 0.32512 -0.175006)
			(end 0.32512 0.175006)
			(stroke
				(width 0.1)
				(type default)
			)
			(layer "F.Fab")
		)
		(fp_line
			(start -0.32512 -0.175006)
			(end 0.32512 -0.175006)
			(stroke
				(width 0.1)
				(type default)
			)
			(layer "F.Fab")
		)
		(fp_line
			(start 0.32512 0.175006)
			(end -0.32512 0.175006)
			(stroke
				(width 0.1)
				(type default)
			)
			(layer "F.Fab")
		)
		(fp_line
			(start -0.32512 0.175006)
			(end -0.32512 -0.175006)
			(stroke
				(width 0.1)
				(type default)
			)
			(layer "F.Fab")
		)
		(pad "1" smd rect
			(at -0.2667 0 90)
			(size 0.3048 0.381)
			(layers "F.Cu" "F.Mask" "F.Paste")
			(net "USB2_CPU0_P0_HUB2_R_DN")
		)
		(pad "2" smd rect
			(at 0.2667 0 270)
			(size 0.3048 0.381)
			(layers "F.Cu" "F.Mask" "F.Paste")
			(net "USB2_HUB_EXT_DN")
		)
	)
	(footprint ""
		(layer "F.Cu")
		(at 383.771902 -177.88636 -90)
		(property "Reference" "PC544_3"
			(at 0 0 270)
			(layer "F.SilkS")
			(hide yes)
			(effects
				(font
					(size 1.27 1.27)
				)
			)
		)
		(property "Value" ""
			(at 0 0 270)
			(layer "F.Fab")
			(effects
				(font
					(size 1.27 1.27)
				)
			)
		)
		(duplicate_pad_numbers_are_jumpers no)
		(fp_line
			(start -0.7874 0.4064)
			(end -0.7874 -0.4064)
			(stroke
				(width 0.1524)
				(type default)
			)
			(layer "F.SilkS")
		)
		(fp_line
			(start 0.7874 0.4064)
			(end -0.7874 0.4064)
			(stroke
				(width 0.1524)
				(type default)
			)
			(layer "F.SilkS")
		)
		(fp_line
			(start -0.7874 -0.4064)
			(end 0.7874 -0.4064)
			(stroke
				(width 0.1524)
				(type default)
			)
			(layer "F.SilkS")
		)
		(fp_line
			(start 0.7874 -0.4064)
			(end 0.7874 0.4064)
			(stroke
				(width 0.1524)
				(type default)
			)
			(layer "F.SilkS")
		)
		(fp_line
			(start -0.67945 0.3048)
			(end -0.67945 -0.305054)
			(stroke
				(width 0.1)
				(type default)
			)
			(layer "F.Fab")
		)
		(fp_line
			(start -0.12065 0.3048)
			(end -0.67945 0.3048)
			(stroke
				(width 0.1)
				(type default)
			)
			(layer "F.Fab")
		)
		(fp_line
			(start 0.120396 0.3048)
			(end 0.120396 0.2794)
			(stroke
				(width 0.1)
				(type default)
			)
			(layer "F.Fab")
		)
		(fp_line
			(start 0.67945 0.3048)
			(end 0.120396 0.3048)
			(stroke
				(width 0.1)
				(type default)
			)
			(layer "F.Fab")
		)
		(fp_line
			(start -0.12065 0.2794)
			(end -0.12065 0.3048)
			(stroke
				(width 0.1)
				(type default)
			)
			(layer "F.Fab")
		)
		(fp_line
			(start 0.120396 0.2794)
			(end -0.12065 0.2794)
			(stroke
				(width 0.1)
				(type default)
			)
			(layer "F.Fab")
		)
		(fp_line
			(start -0.12065 -0.2794)
			(end 0.12065 -0.2794)
			(stroke
				(width 0.1)
				(type default)
			)
			(layer "F.Fab")
		)
		(fp_line
			(start 0.12065 -0.2794)
			(end 0.12065 -0.3048)
			(stroke
				(width 0.1)
				(type default)
			)
			(layer "F.Fab")
		)
		(fp_line
			(start 0.12065 -0.3048)
			(end 0.67945 -0.3048)
			(stroke
				(width 0.1)
				(type default)
			)
			(layer "F.Fab")
		)
		(fp_line
			(start 0.67945 -0.3048)
			(end 0.67945 0.3048)
			(stroke
				(width 0.1)
				(type default)
			)
			(layer "F.Fab")
		)
		(fp_line
			(start -0.67945 -0.305054)
			(end -0.12065 -0.305054)
			(stroke
				(width 0.1)
				(type default)
			)
			(layer "F.Fab")
		)
		(fp_line
			(start -0.12065 -0.305054)
			(end -0.12065 -0.2794)
			(stroke
				(width 0.1)
				(type default)
			)
			(layer "F.Fab")
		)
		(pad "1" smd circle
			(at -0.40005 0 270)
			(size 0 0)
			(layers "F.Cu" "F.Mask" "F.Paste")
			(net "PVDDCR_CPU0_P0_VCCS")
		)
		(pad "2" smd circle
			(at 0.40005 0 270)
			(size 0 0)
			(layers "F.Cu" "F.Mask" "F.Paste")
			(net "GND")
		)
	)
)
